(kicad_pcb
	(version 20260206)
	(generator "pcbnew")
	(generator_version "10.0")
	(general
		(thickness 1.6)
		(legacy_teardrops no)
	)
	(paper "A4")
	(title_block
		(title "01162023_DA0F0TEBIF0_F0T_Expander_BD_F_brd_V02_OCP.brd")
		(comment 1 "Grand Teton / footprints 8966-8973 of 9728")
	)
	(layers
		(0 "F.Cu" signal "TOP")
		(4 "In1.Cu" signal "GND")
		(6 "In2.Cu" signal "VCC")
		(8 "In3.Cu" signal "VCC1")
		(10 "In4.Cu" signal "GND1")
		(12 "In5.Cu" signal "IN1")
		(14 "In6.Cu" signal "GND2")
		(16 "In7.Cu" signal "IN2")
		(18 "In8.Cu" signal "GND3")
		(20 "In9.Cu" signal "IN3")
		(22 "In10.Cu" signal "GND4")
		(24 "In11.Cu" signal "IN4")
		(26 "In12.Cu" signal "GND5")
		(28 "In13.Cu" signal "IN5")
		(30 "In14.Cu" signal "GND6")
		(32 "In15.Cu" signal "IN6")
		(34 "In16.Cu" signal "GND7")
		(2 "B.Cu" signal "BOTTOM")
		(9 "F.Adhes" user "F.Adhesive")
		(11 "B.Adhes" user "B.Adhesive")
		(13 "F.Paste" user "Package Geometry/Pastemask Top")
		(15 "B.Paste" user "Package Geometry/Pastemask Bottom")
		(5 "F.SilkS" user "Ref Des/Silkscreen Top")
		(7 "B.SilkS" user "Ref Des/Silkscreen Bottom")
		(1 "F.Mask" user "Board Geometry/Soldermask Top")
		(3 "B.Mask" user "Board Geometry/Soldermask Bottom")
		(17 "Dwgs.User" user "User.Drawings")
		(19 "Cmts.User" user "User.Comments")
		(21 "Eco1.User" user "User.Eco1")
		(23 "Eco2.User" user "User.Eco2")
		(25 "Edge.Cuts" user "Board Geometry/Outline")
		(27 "Margin" user)
		(31 "F.CrtYd" user "Package Geometry/Place Bound Top")
		(29 "B.CrtYd" user "Package Geometry/Place Bound Bottom")
		(35 "F.Fab" user "Ref Des/Assembly Top")
		(33 "B.Fab" user "Ref Des/Assembly Bottom")
	)
	(footprint ""
		(layer "B.Cu")
		(at 344.641424 -323.15531 -90)
		(property "Reference" "R6507"
			(at 0 0 90)
			(layer "B.SilkS")
			(hide yes)
			(effects
				(font
					(size 1.27 1.27)
				)
				(justify mirror)
			)
		)
		(property "Value" ""
			(at 0 0 90)
			(layer "B.Fab")
			(effects
				(font
					(size 1.27 1.27)
				)
				(justify mirror)
			)
		)
		(duplicate_pad_numbers_are_jumpers no)
		(fp_line
			(start -0.7874 0.4064)
			(end 0.7874 0.4064)
			(stroke
				(width 0.1524)
				(type default)
			)
			(layer "B.SilkS")
		)
		(fp_line
			(start 0.7874 0.4064)
			(end 0.7874 -0.4064)
			(stroke
				(width 0.1524)
				(type default)
			)
			(layer "B.SilkS")
		)
		(fp_line
			(start -0.7874 -0.4064)
			(end -0.7874 0.4064)
			(stroke
				(width 0.1524)
				(type default)
			)
			(layer "B.SilkS")
		)
		(fp_line
			(start 0.7874 -0.4064)
			(end -0.7874 -0.4064)
			(stroke
				(width 0.1524)
				(type default)
			)
			(layer "B.SilkS")
		)
		(fp_line
			(start -0.67945 0.3048)
			(end -0.120396 0.3048)
			(stroke
				(width 0.1)
				(type default)
			)
			(layer "B.Fab")
		)
		(fp_line
			(start -0.120396 0.3048)
			(end -0.120396 0.2794)
			(stroke
				(width 0.1)
				(type default)
			)
			(layer "B.Fab")
		)
		(fp_line
			(start 0.12065 0.3048)
			(end 0.67945 0.3048)
			(stroke
				(width 0.1)
				(type default)
			)
			(layer "B.Fab")
		)
		(fp_line
			(start 0.67945 0.3048)
			(end 0.67945 -0.305054)
			(stroke
				(width 0.1)
				(type default)
			)
			(layer "B.Fab")
		)
		(fp_line
			(start -0.120396 0.2794)
			(end 0.12065 0.2794)
			(stroke
				(width 0.1)
				(type default)
			)
			(layer "B.Fab")
		)
		(fp_line
			(start 0.12065 0.2794)
			(end 0.12065 0.3048)
			(stroke
				(width 0.1)
				(type default)
			)
			(layer "B.Fab")
		)
		(fp_line
			(start -0.12065 -0.2794)
			(end -0.12065 -0.3048)
			(stroke
				(width 0.1)
				(type default)
			)
			(layer "B.Fab")
		)
		(fp_line
			(start 0.12065 -0.2794)
			(end -0.12065 -0.2794)
			(stroke
				(width 0.1)
				(type default)
			)
			(layer "B.Fab")
		)
		(fp_line
			(start -0.67945 -0.3048)
			(end -0.67945 0.3048)
			(stroke
				(width 0.1)
				(type default)
			)
			(layer "B.Fab")
		)
		(fp_line
			(start -0.12065 -0.3048)
			(end -0.67945 -0.3048)
			(stroke
				(width 0.1)
				(type default)
			)
			(layer "B.Fab")
		)
		(fp_line
			(start 0.12065 -0.305054)
			(end 0.12065 -0.2794)
			(stroke
				(width 0.1)
				(type default)
			)
			(layer "B.Fab")
		)
		(fp_line
			(start 0.67945 -0.305054)
			(end 0.12065 -0.305054)
			(stroke
				(width 0.1)
				(type default)
			)
			(layer "B.Fab")
		)
		(pad "1" smd circle
			(at 0.40005 0 90)
			(size 0 0)
			(layers "B.Cu" "B.Mask" "B.Paste")
			(net "P0V8_SERDES_VDDA_PEX2")
		)
		(pad "2" smd circle
			(at -0.40005 0 90)
			(size 0 0)
			(layers "B.Cu" "B.Mask" "B.Paste")
			(net "P0V8_SERDES_VDDA_PEX2_C2")
		)
	)
	(footprint ""
		(layer "B.Cu")
		(at 178.599846 -292.099746 90)
		(property "Reference" "C1461"
			(at 0 0 90)
			(layer "B.SilkS")
			(hide yes)
			(effects
				(font
					(size 1.27 1.27)
				)
				(justify mirror)
			)
		)
		(property "Value" ""
			(at 0 0 90)
			(layer "B.Fab")
			(effects
				(font
					(size 1.27 1.27)
				)
				(justify mirror)
			)
		)
		(duplicate_pad_numbers_are_jumpers no)
		(fp_line
			(start 0.299974 -0.150114)
			(end -0.299974 -0.150114)
			(stroke
				(width 0.1)
				(type default)
			)
			(layer "B.Fab")
		)
		(fp_line
			(start -0.299974 -0.150114)
			(end -0.299974 0.150114)
			(stroke
				(width 0.1)
				(type default)
			)
			(layer "B.Fab")
		)
		(fp_line
			(start 0.299974 0.150114)
			(end 0.299974 -0.150114)
			(stroke
				(width 0.1)
				(type default)
			)
			(layer "B.Fab")
		)
		(fp_line
			(start -0.299974 0.150114)
			(end 0.299974 0.150114)
			(stroke
				(width 0.1)
				(type default)
			)
			(layer "B.Fab")
		)
		(pad "1" smd rect
			(at 0.2667 0 270)
			(size 0.3048 0.381)
			(layers "B.Cu" "B.Mask" "B.Paste")
			(net "P0V8_SERDES_VDDA_PEX1")
		)
		(pad "2" smd rect
			(at -0.2667 0 270)
			(size 0.3048 0.381)
			(layers "B.Cu" "B.Mask" "B.Paste")
			(net "GND")
		)
	)
	(footprint ""
		(layer "B.Cu")
		(at 358.834944 -293.506906 90)
		(property "Reference" "PC181"
			(at 0 0 90)
			(layer "B.SilkS")
			(hide yes)
			(effects
				(font
					(size 1.27 1.27)
				)
				(justify mirror)
			)
		)
		(property "Value" ""
			(at 0 0 90)
			(layer "B.Fab")
			(effects
				(font
					(size 1.27 1.27)
				)
				(justify mirror)
			)
		)
		(duplicate_pad_numbers_are_jumpers no)
		(fp_line
			(start 1.524 -0.762)
			(end -1.524 -0.762)
			(stroke
				(width 0.1524)
				(type default)
			)
			(layer "B.SilkS")
		)
		(fp_line
			(start -1.524 -0.762)
			(end -1.524 0.762)
			(stroke
				(width 0.1524)
				(type default)
			)
			(layer "B.SilkS")
		)
		(fp_line
			(start 1.524 0.762)
			(end 1.524 -0.762)
			(stroke
				(width 0.1524)
				(type default)
			)
			(layer "B.SilkS")
		)
		(fp_line
			(start -1.524 0.762)
			(end 1.524 0.762)
			(stroke
				(width 0.1524)
				(type default)
			)
			(layer "B.SilkS")
		)
		(fp_line
			(start 1.1049 -0.724916)
			(end 1.1049 0.724916)
			(stroke
				(width 0.1)
				(type default)
			)
			(layer "B.Fab")
		)
		(fp_line
			(start -1.1049 -0.724916)
			(end 1.1049 -0.724916)
			(stroke
				(width 0.1)
				(type default)
			)
			(layer "B.Fab")
		)
		(fp_line
			(start 1.1049 0.724916)
			(end -1.1049 0.724916)
			(stroke
				(width 0.1)
				(type default)
			)
			(layer "B.Fab")
		)
		(fp_line
			(start -1.1049 0.724916)
			(end -1.1049 -0.724916)
			(stroke
				(width 0.1)
				(type default)
			)
			(layer "B.Fab")
		)
		(pad "1" smd rect
			(at 0.889 0 90)
			(size 1.016 1.27)
			(layers "B.Cu" "B.Mask" "B.Paste")
			(net "P0V8_PEX3")
		)
		(pad "2" smd rect
			(at -0.889 0 90)
			(size 1.016 1.27)
			(layers "B.Cu" "B.Mask" "B.Paste")
			(net "GND")
		)
	)
	(footprint ""
		(layer "B.Cu")
		(at 425.841922 -104.120696 180)
		(property "Reference" "R372"
			(at 0 0 0)
			(layer "B.SilkS")
			(hide yes)
			(effects
				(font
					(size 1.27 1.27)
				)
				(justify mirror)
			)
		)
		(property "Value" ""
			(at 0 0 0)
			(layer "B.Fab")
			(effects
				(font
					(size 1.27 1.27)
				)
				(justify mirror)
			)
		)
		(duplicate_pad_numbers_are_jumpers no)
		(fp_line
			(start 0.7874 0.4064)
			(end 0.7874 -0.4064)
			(stroke
				(width 0.1524)
				(type default)
			)
			(layer "B.SilkS")
		)
		(fp_line
			(start 0.7874 -0.4064)
			(end -0.7874 -0.4064)
			(stroke
				(width 0.1524)
				(type default)
			)
			(layer "B.SilkS")
		)
		(fp_line
			(start -0.7874 0.4064)
			(end 0.7874 0.4064)
			(stroke
				(width 0.1524)
				(type default)
			)
			(layer "B.SilkS")
		)
		(fp_line
			(start -0.7874 -0.4064)
			(end -0.7874 0.4064)
			(stroke
				(width 0.1524)
				(type default)
			)
			(layer "B.SilkS")
		)
		(fp_line
			(start 0.67945 0.3048)
			(end 0.67945 -0.305054)
			(stroke
				(width 0.1)
				(type default)
			)
			(layer "B.Fab")
		)
		(fp_line
			(start 0.67945 -0.305054)
			(end 0.12065 -0.305054)
			(stroke
				(width 0.1)
				(type default)
			)
			(layer "B.Fab")
		)
		(fp_line
			(start 0.12065 0.3048)
			(end 0.67945 0.3048)
			(stroke
				(width 0.1)
				(type default)
			)
			(layer "B.Fab")
		)
		(fp_line
			(start 0.12065 0.2794)
			(end 0.12065 0.3048)
			(stroke
				(width 0.1)
				(type default)
			)
			(layer "B.Fab")
		)
		(fp_line
			(start 0.12065 -0.2794)
			(end -0.12065 -0.2794)
			(stroke
				(width 0.1)
				(type default)
			)
			(layer "B.Fab")
		)
		(fp_line
			(start 0.12065 -0.305054)
			(end 0.12065 -0.2794)
			(stroke
				(width 0.1)
				(type default)
			)
			(layer "B.Fab")
		)
		(fp_line
			(start -0.120396 0.3048)
			(end -0.120396 0.2794)
			(stroke
				(width 0.1)
				(type default)
			)
			(layer "B.Fab")
		)
		(fp_line
			(start -0.120396 0.2794)
			(end 0.12065 0.2794)
			(stroke
				(width 0.1)
				(type default)
			)
			(layer "B.Fab")
		)
		(fp_line
			(start -0.12065 -0.2794)
			(end -0.12065 -0.3048)
			(stroke
				(width 0.1)
				(type default)
			)
			(layer "B.Fab")
		)
		(fp_line
			(start -0.12065 -0.3048)
			(end -0.67945 -0.3048)
			(stroke
				(width 0.1)
				(type default)
			)
			(layer "B.Fab")
		)
		(fp_line
			(start -0.67945 0.3048)
			(end -0.120396 0.3048)
			(stroke
				(width 0.1)
				(type default)
			)
			(layer "B.Fab")
		)
		(fp_line
			(start -0.67945 -0.3048)
			(end -0.67945 0.3048)
			(stroke
				(width 0.1)
				(type default)
			)
			(layer "B.Fab")
		)
		(pad "1" smd circle
			(at 0.40005 0)
			(size 0 0)
			(layers "B.Cu" "B.Mask" "B.Paste")
			(net "NCSI_NIC7_CRS_DV")
		)
		(pad "2" smd circle
			(at -0.40005 0)
			(size 0 0)
			(layers "B.Cu" "B.Mask" "B.Paste")
			(net "GND")
		)
	)
	(footprint ""
		(layer "B.Cu")
		(at 125.710188 -261.15391)
		(property "Reference" "PR7141"
			(at 0 0 0)
			(layer "B.SilkS")
			(hide yes)
			(effects
				(font
					(size 1.27 1.27)
				)
				(justify mirror)
			)
		)
		(property "Value" ""
			(at 0 0 0)
			(layer "B.Fab")
			(effects
				(font
					(size 1.27 1.27)
				)
				(justify mirror)
			)
		)
		(duplicate_pad_numbers_are_jumpers no)
		(fp_line
			(start -0.7874 -0.4064)
			(end -0.7874 0.4064)
			(stroke
				(width 0.1524)
				(type default)
			)
			(layer "B.SilkS")
		)
		(fp_line
			(start -0.7874 0.4064)
			(end 0.7874 0.4064)
			(stroke
				(width 0.1524)
				(type default)
			)
			(layer "B.SilkS")
		)
		(fp_line
			(start 0.7874 -0.4064)
			(end -0.7874 -0.4064)
			(stroke
				(width 0.1524)
				(type default)
			)
			(layer "B.SilkS")
		)
		(fp_line
			(start 0.7874 0.4064)
			(end 0.7874 -0.4064)
			(stroke
				(width 0.1524)
				(type default)
			)
			(layer "B.SilkS")
		)
		(fp_line
			(start -0.67945 -0.3048)
			(end -0.67945 0.3048)
			(stroke
				(width 0.1)
				(type default)
			)
			(layer "B.Fab")
		)
		(fp_line
			(start -0.67945 0.3048)
			(end -0.120396 0.3048)
			(stroke
				(width 0.1)
				(type default)
			)
			(layer "B.Fab")
		)
		(fp_line
			(start -0.12065 -0.3048)
			(end -0.67945 -0.3048)
			(stroke
				(width 0.1)
				(type default)
			)
			(layer "B.Fab")
		)
		(fp_line
			(start -0.12065 -0.2794)
			(end -0.12065 -0.3048)
			(stroke
				(width 0.1)
				(type default)
			)
			(layer "B.Fab")
		)
		(fp_line
			(start -0.120396 0.2794)
			(end 0.12065 0.2794)
			(stroke
				(width 0.1)
				(type default)
			)
			(layer "B.Fab")
		)
		(fp_line
			(start -0.120396 0.3048)
			(end -0.120396 0.2794)
			(stroke
				(width 0.1)
				(type default)
			)
			(layer "B.Fab")
		)
		(fp_line
			(start 0.12065 -0.305054)
			(end 0.12065 -0.2794)
			(stroke
				(width 0.1)
				(type default)
			)
			(layer "B.Fab")
		)
		(fp_line
			(start 0.12065 -0.2794)
			(end -0.12065 -0.2794)
			(stroke
				(width 0.1)
				(type default)
			)
			(layer "B.Fab")
		)
		(fp_line
			(start 0.12065 0.2794)
			(end 0.12065 0.3048)
			(stroke
				(width 0.1)
				(type default)
			)
			(layer "B.Fab")
		)
		(fp_line
			(start 0.12065 0.3048)
			(end 0.67945 0.3048)
			(stroke
				(width 0.1)
				(type default)
			)
			(layer "B.Fab")
		)
		(fp_line
			(start 0.67945 -0.305054)
			(end 0.12065 -0.305054)
			(stroke
				(width 0.1)
				(type default)
			)
			(layer "B.Fab")
		)
		(fp_line
			(start 0.67945 0.3048)
			(end 0.67945 -0.305054)
			(stroke
				(width 0.1)
				(type default)
			)
			(layer "B.Fab")
		)
		(pad "1" smd circle
			(at 0.40005 0 180)
			(size 0 0)
			(layers "B.Cu" "B.Mask" "B.Paste")
			(net "GND")
		)
		(pad "2" smd circle
			(at -0.40005 0 180)
			(size 0 0)
			(layers "B.Cu" "B.Mask" "B.Paste")
			(net "P0V8_PEX0_SVID")
		)
	)
	(footprint ""
		(layer "B.Cu")
		(at 170.049952 -288.299906 90)
		(property "Reference" "C3097"
			(at 0 0 90)
			(layer "B.SilkS")
			(hide yes)
			(effects
				(font
					(size 1.27 1.27)
				)
				(justify mirror)
			)
		)
		(property "Value" ""
			(at 0 0 90)
			(layer "B.Fab")
			(effects
				(font
					(size 1.27 1.27)
				)
				(justify mirror)
			)
		)
		(duplicate_pad_numbers_are_jumpers no)
		(fp_line
			(start 0.299974 -0.150114)
			(end -0.299974 -0.150114)
			(stroke
				(width 0.1)
				(type default)
			)
			(layer "B.Fab")
		)
		(fp_line
			(start -0.299974 -0.150114)
			(end -0.299974 0.150114)
			(stroke
				(width 0.1)
				(type default)
			)
			(layer "B.Fab")
		)
		(fp_line
			(start 0.299974 0.150114)
			(end 0.299974 -0.150114)
			(stroke
				(width 0.1)
				(type default)
			)
			(layer "B.Fab")
		)
		(fp_line
			(start -0.299974 0.150114)
			(end 0.299974 0.150114)
			(stroke
				(width 0.1)
				(type default)
			)
			(layer "B.Fab")
		)
		(pad "1" smd rect
			(at 0.2667 0 270)
			(size 0.3048 0.381)
			(layers "B.Cu" "B.Mask" "B.Paste")
			(net "P1V25_PEX1")
		)
		(pad "2" smd rect
			(at -0.2667 0 270)
			(size 0.3048 0.381)
			(layers "B.Cu" "B.Mask" "B.Paste")
			(net "GND")
		)
	)
	(footprint ""
		(layer "B.Cu")
		(at 102.016306 -329.68311)
		(property "Reference" "R4227"
			(at 0 0 0)
			(layer "B.SilkS")
			(hide yes)
			(effects
				(font
					(size 1.27 1.27)
				)
				(justify mirror)
			)
		)
		(property "Value" ""
			(at 0 0 0)
			(layer "B.Fab")
			(effects
				(font
					(size 1.27 1.27)
				)
				(justify mirror)
			)
		)
		(duplicate_pad_numbers_are_jumpers no)
		(fp_line
			(start -0.7874 -0.4064)
			(end -0.7874 0.4064)
			(stroke
				(width 0.1524)
				(type default)
			)
			(layer "B.SilkS")
		)
		(fp_line
			(start -0.7874 0.4064)
			(end 0.7874 0.4064)
			(stroke
				(width 0.1524)
				(type default)
			)
			(layer "B.SilkS")
		)
		(fp_line
			(start 0.7874 -0.4064)
			(end -0.7874 -0.4064)
			(stroke
				(width 0.1524)
				(type default)
			)
			(layer "B.SilkS")
		)
		(fp_line
			(start 0.7874 0.4064)
			(end 0.7874 -0.4064)
			(stroke
				(width 0.1524)
				(type default)
			)
			(layer "B.SilkS")
		)
		(fp_line
			(start -0.67945 -0.3048)
			(end -0.67945 0.3048)
			(stroke
				(width 0.1)
				(type default)
			)
			(layer "B.Fab")
		)
		(fp_line
			(start -0.67945 0.3048)
			(end -0.120396 0.3048)
			(stroke
				(width 0.1)
				(type default)
			)
			(layer "B.Fab")
		)
		(fp_line
			(start -0.12065 -0.3048)
			(end -0.67945 -0.3048)
			(stroke
				(width 0.1)
				(type default)
			)
			(layer "B.Fab")
		)
		(fp_line
			(start -0.12065 -0.2794)
			(end -0.12065 -0.3048)
			(stroke
				(width 0.1)
				(type default)
			)
			(layer "B.Fab")
		)
		(fp_line
			(start -0.120396 0.2794)
			(end 0.12065 0.2794)
			(stroke
				(width 0.1)
				(type default)
			)
			(layer "B.Fab")
		)
		(fp_line
			(start -0.120396 0.3048)
			(end -0.120396 0.2794)
			(stroke
				(width 0.1)
				(type default)
			)
			(layer "B.Fab")
		)
		(fp_line
			(start 0.12065 -0.305054)
			(end 0.12065 -0.2794)
			(stroke
				(width 0.1)
				(type default)
			)
			(layer "B.Fab")
		)
		(fp_line
			(start 0.12065 -0.2794)
			(end -0.12065 -0.2794)
			(stroke
				(width 0.1)
				(type default)
			)
			(layer "B.Fab")
		)
		(fp_line
			(start 0.12065 0.2794)
			(end 0.12065 0.3048)
			(stroke
				(width 0.1)
				(type default)
			)
			(layer "B.Fab")
		)
		(fp_line
			(start 0.12065 0.3048)
			(end 0.67945 0.3048)
			(stroke
				(width 0.1)
				(type default)
			)
			(layer "B.Fab")
		)
		(fp_line
			(start 0.67945 -0.305054)
			(end 0.12065 -0.305054)
			(stroke
				(width 0.1)
				(type default)
			)
			(layer "B.Fab")
		)
		(fp_line
			(start 0.67945 0.3048)
			(end 0.67945 -0.305054)
			(stroke
				(width 0.1)
				(type default)
			)
			(layer "B.Fab")
		)
		(pad "1" smd circle
			(at 0.40005 0 180)
			(size 0 0)
			(layers "B.Cu" "B.Mask" "B.Paste")
			(net "PEX_REF_CLK_BUFFER_EN_N")
		)
		(pad "2" smd circle
			(at -0.40005 0 180)
			(size 0 0)
			(layers "B.Cu" "B.Mask" "B.Paste")
			(net "GND")
		)
	)
	(footprint ""
		(layer "B.Cu")
		(at 228.267768 -221.904052 90)
		(property "Reference" "C2025"
			(at 0 0 90)
			(layer "B.SilkS")
			(hide yes)
			(effects
				(font
					(size 1.27 1.27)
				)
				(justify mirror)
			)
		)
		(property "Value" ""
			(at 0 0 90)
			(layer "B.Fab")
			(effects
				(font
					(size 1.27 1.27)
				)
				(justify mirror)
			)
		)
		(duplicate_pad_numbers_are_jumpers no)
		(fp_line
			(start 0.69215 -0.2921)
			(end -0.69215 -0.2921)
			(stroke
				(width 0.1524)
				(type default)
			)
			(layer "B.SilkS")
		)
		(fp_line
			(start -0.69215 -0.2921)
			(end -0.69215 0.2921)
			(stroke
				(width 0.1524)
				(type default)
			)
			(layer "B.SilkS")
		)
		(fp_line
			(start 0.69215 0.2921)
			(end 0.69215 -0.2921)
			(stroke
				(width 0.1524)
				(type default)
			)
			(layer "B.SilkS")
		)
		(fp_line
			(start -0.69215 0.2921)
			(end 0.69215 0.2921)
			(stroke
				(width 0.1524)
				(type default)
			)
			(layer "B.SilkS")
		)
		(fp_line
			(start 0.51435 -0.2794)
			(end -0.51435 -0.2794)
			(stroke
				(width 0.1)
				(type default)
			)
			(layer "B.Fab")
		)
		(fp_line
			(start -0.51435 -0.2794)
			(end -0.51435 0.2794)
			(stroke
				(width 0.1)
				(type default)
			)
			(layer "B.Fab")
		)
		(fp_line
			(start 0.51435 0.2794)
			(end 0.51435 -0.2794)
			(stroke
				(width 0.1)
				(type default)
			)
			(layer "B.Fab")
		)
		(fp_line
			(start -0.51435 0.2794)
			(end 0.51435 0.2794)
			(stroke
				(width 0.1)
				(type default)
			)
			(layer "B.Fab")
		)
		(pad "1" smd circle
			(at 0.40005 0 270)
			(size 0 0)
			(layers "B.Cu" "B.Mask" "B.Paste")
			(net "P3V3_AUX")
		)
		(pad "2" smd circle
			(at -0.40005 0 270)
			(size 0 0)
			(layers "B.Cu" "B.Mask" "B.Paste")
			(net "GND")
		)
		(zone
			(layer "B.Cu")
			(hatch none 0.5)
			(connect_pads
				(clearance 0)
			)
			(min_thickness 0.25)
			(keepout
				(tracks not_allowed)
				(vias allowed)
				(pads allowed)
				(copperpour not_allowed)
				(footprints allowed)
			)
			(placement
				(enabled no)
				(sheetname "")
			)
			(fill
				(thermal_gap 0.5)
				(thermal_bridge_width 0.5)
				(island_removal_mode 0)
			)
			(polygon
				(pts
					(xy 228.355398 -222.094552) (xy 228.413564 -222.003112) (xy 228.413564 -221.803722) (xy 228.355398 -221.713552)
					(xy 228.180138 -221.713552) (xy 228.121718 -221.803722) (xy 228.121718 -222.003112) (xy 228.179884 -222.094552)
				)
			)
		)
	)
)
